(kicad_pcb
	(version 20260206)
	(generator "pcbnew")
	(generator_version "10.0")
	(general
		(thickness 1.6)
		(legacy_teardrops no)
	)
	(paper "A4")
	(title_block
		(title "baseboard — 13948-1b.1110WZS1818.brd")
		(comment 1 "Honey Badger (Wiwynn) / footprint 84 of 2523 (GF1), pads 1-108 of 164")
	)
	(layers
		(0 "F.Cu" signal "TOP")
		(4 "In1.Cu" signal "L2GND")
		(6 "In2.Cu" signal "L3")
		(8 "In3.Cu" signal "L4VCC")
		(10 "In4.Cu" signal "L5VCC")
		(12 "In5.Cu" signal "L6")
		(14 "In6.Cu" signal "L7GND")
		(2 "B.Cu" signal "BOTTOM")
		(9 "F.Adhes" user "F.Adhesive")
		(11 "B.Adhes" user "B.Adhesive")
		(13 "F.Paste" user "Package Geometry/Pastemask Top")
		(15 "B.Paste" user "Package Geometry/Pastemask Bottom")
		(5 "F.SilkS" user "Ref Des/Silkscreen Top")
		(7 "B.SilkS" user "Ref Des/Silkscreen Bottom")
		(1 "F.Mask" user "Board Geometry/Soldermask Top")
		(3 "B.Mask" user "Board Geometry/Soldermask Bottom")
		(17 "Dwgs.User" user "User.Drawings")
		(19 "Cmts.User" user "User.Comments")
		(21 "Eco1.User" user "User.Eco1")
		(23 "Eco2.User" user "User.Eco2")
		(25 "Edge.Cuts" user "Board Geometry/Outline")
		(27 "Margin" user)
		(31 "F.CrtYd" user "Package Geometry/Place Bound Top")
		(29 "B.CrtYd" user "Package Geometry/Place Bound Bottom")
		(35 "F.Fab" user "Ref Des/Assembly Top")
		(33 "B.Fab" user "Ref Des/Assembly Bottom")
	)
	(footprint ""
		(layer "F.Cu")
		(at 139.500102 -258.59994 180)
		(property "Reference" "GF1"
			(at 0 0 180)
			(layer "F.SilkS")
			(hide yes)
			(effects
				(font
					(size 1.27 1.27)
				)
			)
		)
		(property "Value" "GF-X16-U"
			(at 12.048744 -9.339834 180)
			(unlocked yes)
			(layer "F.Fab")
			(hide yes)
			(effects
				(font
					(size 1.016 1.016)
					(thickness 0.1524)
				)
			)
		)
		(property "Device Type" "GF-X16-U"
			(at 12.048744 -10.863834 180)
			(unlocked yes)
			(layer "F.Fab")
			(hide yes)
			(effects
				(font
					(size 1.016 1.016)
					(thickness 0.1524)
				)
			)
		)
		(duplicate_pad_numbers_are_jumpers no)
		(pad "A1" smd rect
			(at -11.49985 -2.5908 180)
			(size 0.7112 3.2004)
			(layers "F.Cu" "F.Mask" "F.Paste")
			(net "GND")
		)
		(pad "A2" smd rect
			(at -10.50036 -2.0955 180)
			(size 0.7112 4.191)
			(layers "F.Cu" "F.Mask" "F.Paste")
			(net "SAS_GF_EXP_RX_DP0")
		)
		(pad "A3" smd rect
			(at -9.4996 -2.0955 180)
			(size 0.7112 4.191)
			(layers "F.Cu" "F.Mask" "F.Paste")
			(net "SAS_GF_EXP_RX_DN0")
		)
		(pad "A4" smd rect
			(at -8.50011 -2.0955 180)
			(size 0.7112 4.191)
			(layers "F.Cu" "F.Mask" "F.Paste")
			(net "GND")
		)
		(pad "A5" smd rect
			(at -7.49935 -2.0955 180)
			(size 0.7112 4.191)
			(layers "F.Cu" "F.Mask" "F.Paste")
			(net "GND")
		)
		(pad "A6" smd rect
			(at -6.49986 -2.0955 180)
			(size 0.7112 4.191)
			(layers "F.Cu" "F.Mask" "F.Paste")
			(net "SAS_GF_EXP_RX_DP1")
		)
		(pad "A7" smd rect
			(at -5.50037 -2.0955 180)
			(size 0.7112 4.191)
			(layers "F.Cu" "F.Mask" "F.Paste")
			(net "SAS_GF_EXP_RX_DN1")
		)
		(pad "A8" smd rect
			(at -4.49961 -2.0955 180)
			(size 0.7112 4.191)
			(layers "F.Cu" "F.Mask" "F.Paste")
			(net "GND")
		)
		(pad "A9" smd rect
			(at -3.50012 -2.0955 180)
			(size 0.7112 4.191)
			(layers "F.Cu" "F.Mask" "F.Paste")
			(net "GND")
		)
		(pad "A10" smd rect
			(at -2.49936 -2.0955 180)
			(size 0.7112 4.191)
			(layers "F.Cu" "F.Mask" "F.Paste")
			(net "SAS_GF_EXP_RX_DP2")
		)
		(pad "A11" smd rect
			(at -1.49987 -2.0955 180)
			(size 0.7112 4.191)
			(layers "F.Cu" "F.Mask" "F.Paste")
			(net "SAS_GF_EXP_RX_DN2")
		)
		(pad "A12" smd rect
			(at 1.49987 -2.0955 180)
			(size 0.7112 4.191)
			(layers "F.Cu" "F.Mask" "F.Paste")
			(net "TRAY_ID")
		)
		(pad "A13" smd rect
			(at 2.50063 -2.0955 180)
			(size 0.7112 4.191)
			(layers "F.Cu" "F.Mask" "F.Paste")
			(net "GND")
		)
		(pad "A14" smd rect
			(at 3.50012 -2.0955 180)
			(size 0.7112 4.191)
			(layers "F.Cu" "F.Mask" "F.Paste")
			(net "SAS_GF_EXP_RX_DP3")
		)
		(pad "A15" smd rect
			(at 4.49961 -2.0955 180)
			(size 0.7112 4.191)
			(layers "F.Cu" "F.Mask" "F.Paste")
			(net "SAS_GF_EXP_RX_DN3")
		)
		(pad "A16" smd rect
			(at 5.50037 -2.0955 180)
			(size 0.7112 4.191)
			(layers "F.Cu" "F.Mask" "F.Paste")
			(net "GND")
		)
		(pad "A17" smd rect
			(at 6.49986 -2.0955 180)
			(size 0.7112 4.191)
			(layers "F.Cu" "F.Mask" "F.Paste")
			(net "GND")
		)
		(pad "A18" smd rect
			(at 7.50062 -2.0955 180)
			(size 0.7112 4.191)
			(layers "F.Cu" "F.Mask" "F.Paste")
			(net "SAS_GF_EXP_RX_DP4")
		)
		(pad "A19" smd rect
			(at 8.50011 -2.0955 180)
			(size 0.7112 4.191)
			(layers "F.Cu" "F.Mask" "F.Paste")
			(net "SAS_GF_EXP_RX_DN4")
		)
		(pad "A20" smd rect
			(at 9.4996 -2.0955 180)
			(size 0.7112 4.191)
			(layers "F.Cu" "F.Mask" "F.Paste")
			(net "GND")
		)
		(pad "A21" smd rect
			(at 10.50036 -2.0955 180)
			(size 0.7112 4.191)
			(layers "F.Cu" "F.Mask" "F.Paste")
			(net "GND")
		)
		(pad "A22" smd rect
			(at 11.49985 -2.0955 180)
			(size 0.7112 4.191)
			(layers "F.Cu" "F.Mask" "F.Paste")
			(net "SAS_GF_EXP_RX_DP5")
		)
		(pad "A23" smd rect
			(at 12.50061 -2.0955 180)
			(size 0.7112 4.191)
			(layers "F.Cu" "F.Mask" "F.Paste")
			(net "SAS_GF_EXP_RX_DN5")
		)
		(pad "A24" smd rect
			(at 13.5001 -2.0955 180)
			(size 0.7112 4.191)
			(layers "F.Cu" "F.Mask" "F.Paste")
			(net "GND")
		)
		(pad "A25" smd rect
			(at 14.49959 -2.0955 180)
			(size 0.7112 4.191)
			(layers "F.Cu" "F.Mask" "F.Paste")
			(net "GND")
		)
		(pad "A26" smd rect
			(at 15.50035 -2.0955 180)
			(size 0.7112 4.191)
			(layers "F.Cu" "F.Mask" "F.Paste")
			(net "SAS_GF_EXP_RX_DP6")
		)
		(pad "A27" smd rect
			(at 16.49984 -2.0955 180)
			(size 0.7112 4.191)
			(layers "F.Cu" "F.Mask" "F.Paste")
			(net "SAS_GF_EXP_RX_DN6")
		)
		(pad "A28" smd rect
			(at 17.5006 -2.0955 180)
			(size 0.7112 4.191)
			(layers "F.Cu" "F.Mask" "F.Paste")
			(net "GND")
		)
		(pad "A29" smd rect
			(at 18.50009 -2.0955 180)
			(size 0.7112 4.191)
			(layers "F.Cu" "F.Mask" "F.Paste")
			(net "GND")
		)
		(pad "A30" smd rect
			(at 19.49958 -2.0955 180)
			(size 0.7112 4.191)
			(layers "F.Cu" "F.Mask" "F.Paste")
			(net "SAS_GF_EXP_RX_DP7")
		)
		(pad "A31" smd rect
			(at 20.50034 -2.0955 180)
			(size 0.7112 4.191)
			(layers "F.Cu" "F.Mask" "F.Paste")
			(net "SAS_GF_EXP_RX_DN7")
		)
		(pad "A32" smd rect
			(at 21.49983 -2.0955 180)
			(size 0.7112 4.191)
			(layers "F.Cu" "F.Mask" "F.Paste")
			(net "GND")
		)
		(pad "A33" smd rect
			(at 22.50059 -2.0955 180)
			(size 0.7112 4.191)
			(layers "F.Cu" "F.Mask" "F.Paste")
			(net "GND")
		)
		(pad "A34" smd rect
			(at 23.50008 -2.0955 180)
			(size 0.7112 4.191)
			(layers "F.Cu" "F.Mask" "F.Paste")
			(net "SAS_GF_EXP_RX_DP8")
		)
		(pad "A35" smd rect
			(at 24.49957 -2.0955 180)
			(size 0.7112 4.191)
			(layers "F.Cu" "F.Mask" "F.Paste")
			(net "SAS_GF_EXP_RX_DN8")
		)
		(pad "A36" smd rect
			(at 25.50033 -2.0955 180)
			(size 0.7112 4.191)
			(layers "F.Cu" "F.Mask" "F.Paste")
			(net "GND")
		)
		(pad "A37" smd rect
			(at 26.49982 -2.0955 180)
			(size 0.7112 4.191)
			(layers "F.Cu" "F.Mask" "F.Paste")
			(net "GND")
		)
		(pad "A38" smd rect
			(at 27.50058 -2.0955 180)
			(size 0.7112 4.191)
			(layers "F.Cu" "F.Mask" "F.Paste")
			(net "SAS_GF_EXP_RX_DP9")
		)
		(pad "A39" smd rect
			(at 28.50007 -2.0955 180)
			(size 0.7112 4.191)
			(layers "F.Cu" "F.Mask" "F.Paste")
			(net "SAS_GF_EXP_RX_DN9")
		)
		(pad "A40" smd rect
			(at 29.49956 -2.0955 180)
			(size 0.7112 4.191)
			(layers "F.Cu" "F.Mask" "F.Paste")
			(net "GND")
		)
		(pad "A41" smd rect
			(at 30.50032 -2.0955 180)
			(size 0.7112 4.191)
			(layers "F.Cu" "F.Mask" "F.Paste")
			(net "SHUTDOWN_RELEASE")
		)
		(pad "A42" smd rect
			(at 31.49981 -2.0955 180)
			(size 0.7112 4.191)
			(layers "F.Cu" "F.Mask" "F.Paste")
			(net "SAS_FAULT_LED1")
		)
		(pad "A43" smd rect
			(at 32.50057 -2.0955 180)
			(size 0.7112 4.191)
			(layers "F.Cu" "F.Mask" "F.Paste")
			(net "SAS_FAULT_LED0")
		)
		(pad "A44" smd rect
			(at 33.50006 -2.0955 180)
			(size 0.7112 4.191)
			(layers "F.Cu" "F.Mask" "F.Paste")
			(net "SAS_FAULT_LED2")
		)
		(pad "A45" smd rect
			(at 34.49955 -2.0955 180)
			(size 0.7112 4.191)
			(layers "F.Cu" "F.Mask" "F.Paste")
			(net "SAS_FAULT_LED3")
		)
		(pad "A46" smd rect
			(at 35.50031 -2.0955 180)
			(size 0.7112 4.191)
			(layers "F.Cu" "F.Mask" "F.Paste")
			(net "SAS_FAULT_LED4")
		)
		(pad "A47" smd rect
			(at 36.4998 -2.0955 180)
			(size 0.7112 4.191)
			(layers "F.Cu" "F.Mask" "F.Paste")
			(net "SAS_FAULT_LED5")
		)
		(pad "A48" smd rect
			(at 37.50056 -2.0955 180)
			(size 0.7112 4.191)
			(layers "F.Cu" "F.Mask" "F.Paste")
			(net "SAS_FAULT_LED6")
		)
		(pad "A49" smd rect
			(at 38.50005 -2.0955 180)
			(size 0.7112 4.191)
			(layers "F.Cu" "F.Mask" "F.Paste")
			(net "SAS_FAULT_LED7")
		)
		(pad "A50" smd rect
			(at 39.49954 -2.0955 180)
			(size 0.7112 4.191)
			(layers "F.Cu" "F.Mask" "F.Paste")
			(net "SAS_FAULT_LED8")
		)
		(pad "A51" smd rect
			(at 40.5003 -2.0955 180)
			(size 0.7112 4.191)
			(layers "F.Cu" "F.Mask" "F.Paste")
			(net "GND")
		)
		(pad "A52" smd rect
			(at 41.49979 -2.0955 180)
			(size 0.7112 4.191)
			(layers "F.Cu" "F.Mask" "F.Paste")
			(net "SAS_GF_EXP_RX_DP10")
		)
		(pad "A53" smd rect
			(at 42.50055 -2.0955 180)
			(size 0.7112 4.191)
			(layers "F.Cu" "F.Mask" "F.Paste")
			(net "SAS_GF_EXP_RX_DN10")
		)
		(pad "A54" smd rect
			(at 43.50004 -2.0955 180)
			(size 0.7112 4.191)
			(layers "F.Cu" "F.Mask" "F.Paste")
			(net "GND")
		)
		(pad "A55" smd rect
			(at 44.49953 -2.0955 180)
			(size 0.7112 4.191)
			(layers "F.Cu" "F.Mask" "F.Paste")
			(net "SAS_I2C_C_BUF_SCL_R")
		)
		(pad "A56" smd rect
			(at 45.50029 -2.0955 180)
			(size 0.7112 4.191)
			(layers "F.Cu" "F.Mask" "F.Paste")
			(net "SAS_I2C_C_BUF_SDA_R")
		)
		(pad "A57" smd rect
			(at 46.49978 -2.0955 180)
			(size 0.7112 4.191)
			(layers "F.Cu" "F.Mask" "F.Paste")
			(net "SAS_I2C_D_BUF_SCL_R")
		)
		(pad "A58" smd rect
			(at 47.50054 -2.0955 180)
			(size 0.7112 4.191)
			(layers "F.Cu" "F.Mask" "F.Paste")
			(net "SAS_I2C_D_BUF_SDA_R")
		)
		(pad "A59" smd rect
			(at 48.50003 -2.0955 180)
			(size 0.7112 4.191)
			(layers "F.Cu" "F.Mask" "F.Paste")
			(net "GND")
		)
		(pad "A60" smd rect
			(at 49.49952 -2.0955 180)
			(size 0.7112 4.191)
			(layers "F.Cu" "F.Mask" "F.Paste")
			(net "SAS_GF_EXP_RX_DP11")
		)
		(pad "A61" smd rect
			(at 50.50028 -2.0955 180)
			(size 0.7112 4.191)
			(layers "F.Cu" "F.Mask" "F.Paste")
			(net "SAS_GF_EXP_RX_DN11")
		)
		(pad "A62" smd rect
			(at 51.49977 -2.0955 180)
			(size 0.7112 4.191)
			(layers "F.Cu" "F.Mask" "F.Paste")
			(net "GND")
		)
		(pad "A63" smd rect
			(at 52.50053 -2.0955 180)
			(size 0.7112 4.191)
			(layers "F.Cu" "F.Mask" "F.Paste")
			(net "GND")
		)
		(pad "A64" smd rect
			(at 53.50002 -2.0955 180)
			(size 0.7112 4.191)
			(layers "F.Cu" "F.Mask" "F.Paste")
			(net "SAS_GF_EXP_RX_DP12")
		)
		(pad "A65" smd rect
			(at 54.50078 -2.0955 180)
			(size 0.7112 4.191)
			(layers "F.Cu" "F.Mask" "F.Paste")
			(net "SAS_GF_EXP_RX_DN12")
		)
		(pad "A66" smd rect
			(at 55.50027 -2.0955 180)
			(size 0.7112 4.191)
			(layers "F.Cu" "F.Mask" "F.Paste")
			(net "GND")
		)
		(pad "A67" smd rect
			(at 56.49976 -2.0955 180)
			(size 0.7112 4.191)
			(layers "F.Cu" "F.Mask" "F.Paste")
			(net "GND")
		)
		(pad "A68" smd rect
			(at 57.50052 -2.0955 180)
			(size 0.7112 4.191)
			(layers "F.Cu" "F.Mask" "F.Paste")
			(net "SAS_GF_EXP_RX_DP13")
		)
		(pad "A69" smd rect
			(at 58.50001 -2.0955 180)
			(size 0.7112 4.191)
			(layers "F.Cu" "F.Mask" "F.Paste")
			(net "SAS_GF_EXP_RX_DN13")
		)
		(pad "A70" smd rect
			(at 59.50077 -2.0955 180)
			(size 0.7112 4.191)
			(layers "F.Cu" "F.Mask" "F.Paste")
			(net "GND")
		)
		(pad "A71" smd rect
			(at 60.50026 -2.0955 180)
			(size 0.7112 4.191)
			(layers "F.Cu" "F.Mask" "F.Paste")
			(net "GND")
		)
		(pad "A72" smd rect
			(at 61.49975 -2.0955 180)
			(size 0.7112 4.191)
			(layers "F.Cu" "F.Mask" "F.Paste")
			(net "SAS_GF_EXP_RX_DP14")
		)
		(pad "A73" smd rect
			(at 62.50051 -2.0955 180)
			(size 0.7112 4.191)
			(layers "F.Cu" "F.Mask" "F.Paste")
			(net "SAS_GF_EXP_RX_DN14")
		)
		(pad "A74" smd rect
			(at 63.5 -2.0955 180)
			(size 0.7112 4.191)
			(layers "F.Cu" "F.Mask" "F.Paste")
			(net "GND")
		)
		(pad "A75" smd rect
			(at 64.50076 -2.0955 180)
			(size 0.7112 4.191)
			(layers "F.Cu" "F.Mask" "F.Paste")
			(net "GND")
		)
		(pad "A76" smd rect
			(at 65.50025 -2.0955 180)
			(size 0.7112 4.191)
			(layers "F.Cu" "F.Mask" "F.Paste")
			(net "SAS_GF_EXP_RX_DP15")
		)
		(pad "A77" smd rect
			(at 66.49974 -2.0955 180)
			(size 0.7112 4.191)
			(layers "F.Cu" "F.Mask" "F.Paste")
			(net "SAS_GF_EXP_RX_DN15")
		)
		(pad "A78" smd rect
			(at 67.5005 -2.0955 180)
			(size 0.7112 4.191)
			(layers "F.Cu" "F.Mask" "F.Paste")
			(net "GND")
		)
		(pad "A79" smd rect
			(at 68.49999 -2.0955 180)
			(size 0.7112 4.191)
			(layers "F.Cu" "F.Mask" "F.Paste")
			(net "PEER_1B_2B_HB")
		)
		(pad "A80" smd rect
			(at 69.50075 -2.0955 180)
			(size 0.7112 4.191)
			(layers "F.Cu" "F.Mask" "F.Paste")
			(net "P12V_PCIE")
		)
		(pad "A81" smd rect
			(at 70.50024 -2.0955 180)
			(size 0.7112 4.191)
			(layers "F.Cu" "F.Mask" "F.Paste")
			(net "P12V_PCIE")
		)
		(pad "A82" smd rect
			(at 71.49973 -2.0955 180)
			(size 0.7112 4.191)
			(layers "F.Cu" "F.Mask" "F.Paste")
			(net "P12V_PCIE")
		)
		(pad "B1" smd rect
			(at -11.49985 -2.3495 180)
			(size 0.7112 4.191)
			(drill
				(offset 0 0.254)
			)
			(layers "F.Cu" "F.Mask" "F.Paste")
			(net "SAS_HDD_PRE15")
		)
		(pad "B2" smd rect
			(at -10.50036 -2.3495 180)
			(size 0.7112 4.191)
			(drill
				(offset 0 0.254)
			)
			(layers "F.Cu" "F.Mask" "F.Paste")
			(net "FCB_HW_REVISION")
		)
		(pad "B3" smd rect
			(at -9.4996 -2.3495 180)
			(size 0.7112 4.191)
			(drill
				(offset 0 0.254)
			)
			(layers "F.Cu" "F.Mask" "F.Paste")
			(net "GND")
		)
		(pad "B4" smd rect
			(at -8.50011 -2.3495 180)
			(size 0.7112 4.191)
			(drill
				(offset 0 0.254)
			)
			(layers "F.Cu" "F.Mask" "F.Paste")
			(net "SAS_EXP_GF_TX_DP0")
		)
		(pad "B5" smd rect
			(at -7.49935 -2.3495 180)
			(size 0.7112 4.191)
			(drill
				(offset 0 0.254)
			)
			(layers "F.Cu" "F.Mask" "F.Paste")
			(net "SAS_EXP_GF_TX_DN0")
		)
		(pad "B6" smd rect
			(at -6.49986 -2.3495 180)
			(size 0.7112 4.191)
			(drill
				(offset 0 0.254)
			)
			(layers "F.Cu" "F.Mask" "F.Paste")
			(net "GND")
		)
		(pad "B7" smd rect
			(at -5.50037 -2.3495 180)
			(size 0.7112 4.191)
			(drill
				(offset 0 0.254)
			)
			(layers "F.Cu" "F.Mask" "F.Paste")
			(net "GND")
		)
		(pad "B8" smd rect
			(at -4.49961 -2.3495 180)
			(size 0.7112 4.191)
			(drill
				(offset 0 0.254)
			)
			(layers "F.Cu" "F.Mask" "F.Paste")
			(net "SAS_EXP_GF_TX_DP1")
		)
		(pad "B9" smd rect
			(at -3.50012 -2.3495 180)
			(size 0.7112 4.191)
			(drill
				(offset 0 0.254)
			)
			(layers "F.Cu" "F.Mask" "F.Paste")
			(net "SAS_EXP_GF_TX_DN1")
		)
		(pad "B10" smd rect
			(at -2.49936 -2.3495 180)
			(size 0.7112 4.191)
			(drill
				(offset 0 0.254)
			)
			(layers "F.Cu" "F.Mask" "F.Paste")
			(net "GND")
		)
		(pad "B11" smd rect
			(at -1.49987 -2.3495 180)
			(size 0.7112 4.191)
			(drill
				(offset 0 0.254)
			)
			(layers "F.Cu" "F.Mask" "F.Paste")
			(net "DPB_HW_REVISION")
		)
		(pad "B12" smd rect
			(at 1.49987 -2.3495 180)
			(size 0.7112 4.191)
			(drill
				(offset 0 0.254)
			)
			(layers "F.Cu" "F.Mask" "F.Paste")
			(net "SAS_EXP_GF_TX_DP2")
		)
		(pad "B13" smd rect
			(at 2.50063 -2.3495 180)
			(size 0.7112 4.191)
			(drill
				(offset 0 0.254)
			)
			(layers "F.Cu" "F.Mask" "F.Paste")
			(net "SAS_EXP_GF_TX_DN2")
		)
		(pad "B14" smd rect
			(at 3.50012 -2.3495 180)
			(size 0.7112 4.191)
			(drill
				(offset 0 0.254)
			)
			(layers "F.Cu" "F.Mask" "F.Paste")
			(net "GND")
		)
		(pad "B15" smd rect
			(at 4.49961 -2.3495 180)
			(size 0.7112 4.191)
			(drill
				(offset 0 0.254)
			)
			(layers "F.Cu" "F.Mask" "F.Paste")
			(net "GND")
		)
		(pad "B16" smd rect
			(at 5.50037 -2.3495 180)
			(size 0.7112 4.191)
			(drill
				(offset 0 0.254)
			)
			(layers "F.Cu" "F.Mask" "F.Paste")
			(net "SAS_EXP_GF_TX_DP3")
		)
		(pad "B17" smd rect
			(at 6.49986 -2.3495 180)
			(size 0.7112 4.191)
			(drill
				(offset 0 0.254)
			)
			(layers "F.Cu" "F.Mask" "F.Paste")
			(net "SAS_EXP_GF_TX_DN3")
		)
		(pad "B18" smd rect
			(at 7.50062 -2.3495 180)
			(size 0.7112 4.191)
			(drill
				(offset 0 0.254)
			)
			(layers "F.Cu" "F.Mask" "F.Paste")
			(net "GND")
		)
		(pad "B19" smd rect
			(at 8.50011 -2.3495 180)
			(size 0.7112 4.191)
			(drill
				(offset 0 0.254)
			)
			(layers "F.Cu" "F.Mask" "F.Paste")
			(net "GND")
		)
		(pad "B20" smd rect
			(at 9.4996 -2.3495 180)
			(size 0.7112 4.191)
			(drill
				(offset 0 0.254)
			)
			(layers "F.Cu" "F.Mask" "F.Paste")
			(net "SAS_EXP_GF_TX_DP4")
		)
		(pad "B21" smd rect
			(at 10.50036 -2.3495 180)
			(size 0.7112 4.191)
			(drill
				(offset 0 0.254)
			)
			(layers "F.Cu" "F.Mask" "F.Paste")
			(net "SAS_EXP_GF_TX_DN4")
		)
		(pad "B22" smd rect
			(at 11.49985 -2.3495 180)
			(size 0.7112 4.191)
			(drill
				(offset 0 0.254)
			)
			(layers "F.Cu" "F.Mask" "F.Paste")
			(net "GND")
		)
		(pad "B23" smd rect
			(at 12.50061 -2.3495 180)
			(size 0.7112 4.191)
			(drill
				(offset 0 0.254)
			)
			(layers "F.Cu" "F.Mask" "F.Paste")
			(net "GND")
		)
		(pad "B24" smd rect
			(at 13.5001 -2.3495 180)
			(size 0.7112 4.191)
			(drill
				(offset 0 0.254)
			)
			(layers "F.Cu" "F.Mask" "F.Paste")
			(net "SAS_EXP_GF_TX_DP5")
		)
		(pad "B25" smd rect
			(at 14.49959 -2.3495 180)
			(size 0.7112 4.191)
			(drill
				(offset 0 0.254)
			)
			(layers "F.Cu" "F.Mask" "F.Paste")
			(net "SAS_EXP_GF_TX_DN5")
		)
		(pad "B26" smd rect
			(at 15.50035 -2.3495 180)
			(size 0.7112 4.191)
			(drill
				(offset 0 0.254)
			)
			(layers "F.Cu" "F.Mask" "F.Paste")
			(net "GND")
		)
	)
)
